# S9S_MB_2U (Grand Teton) — schematic netlist excerpt (pin names and nets, part order shuffled) for the footprints in the layout excerpt that follows; sources: Cadence DE-HDL packaged netlist, KiCad conversion of 03242023_DA0F0TMBIJ0_F0T_Motherboard_J_brd_V01_OCP.brd

R3651  Q_RES  0 5% CHIP  pkg 0402LF  page 152 : A = USB2_P0_R_DP ; B = USB2_HOST_BMC_B_DP
R4791  Q_RES  2K 1% EMPTY  pkg 0402LF  page 307 : A = PWRGD_DSW_PWROK_TRIGGER ; B = GND

(kicad_pcb
	(version 20260206)
	(generator "pcbnew")
	(generator_version "10.0")
	(general
		(thickness 1.6)
		(legacy_teardrops no)
	)
	(paper "A4")
	(title_block
		(title "03242023_DA0F0TMBIJ0_F0T_Motherboard_J_brd_V01_OCP.brd")
		(comment 1 "Grand Teton / footprints 3783-3784 of 6105")
	)
	(layers
		(0 "F.Cu" signal "TOP")
		(4 "In1.Cu" signal "GND")
		(6 "In2.Cu" signal "IN1")
		(8 "In3.Cu" signal "GND1")
		(10 "In4.Cu" signal "IN2")
		(12 "In5.Cu" signal "GND2")
		(14 "In6.Cu" signal "IN3")
		(16 "In7.Cu" signal "GND3")
		(18 "In8.Cu" signal "VCC")
		(20 "In9.Cu" signal "VCC1")
		(22 "In10.Cu" signal "GND4")
		(24 "In11.Cu" signal "IN4")
		(26 "In12.Cu" signal "GND5")
		(28 "In13.Cu" signal "IN5")
		(30 "In14.Cu" signal "GND6")
		(32 "In15.Cu" signal "IN6")
		(34 "In16.Cu" signal "GND7")
		(2 "B.Cu" signal "BOTTOM")
		(9 "F.Adhes" user "F.Adhesive")
		(11 "B.Adhes" user "B.Adhesive")
		(13 "F.Paste" user "Package Geometry/Pastemask Top")
		(15 "B.Paste" user "Package Geometry/Pastemask Bottom")
		(5 "F.SilkS" user "Ref Des/Silkscreen Top")
		(7 "B.SilkS" user "Ref Des/Silkscreen Bottom")
		(1 "F.Mask" user "Board Geometry/Soldermask Top")
		(3 "B.Mask" user "Board Geometry/Soldermask Bottom")
		(17 "Dwgs.User" user "User.Drawings")
		(19 "Cmts.User" user "User.Comments")
		(21 "Eco1.User" user "User.Eco1")
		(23 "Eco2.User" user "User.Eco2")
		(25 "Edge.Cuts" user "Board Geometry/Outline")
		(27 "Margin" user)
		(31 "F.CrtYd" user "Package Geometry/Place Bound Top")
		(29 "B.CrtYd" user "Package Geometry/Place Bound Bottom")
		(35 "F.Fab" user "Ref Des/Assembly Top")
		(33 "B.Fab" user "Ref Des/Assembly Bottom")
	)
	(footprint ""
		(layer "F.Cu")
		(at 15.288006 -104.73563 90)
		(property "Reference" "R3651"
			(at 0 0 90)
			(layer "F.SilkS")
			(hide yes)
			(effects
				(font
					(size 1.27 1.27)
				)
			)
		)
		(property "Value" ""
			(at 0 0 90)
			(layer "F.Fab")
			(effects
				(font
					(size 1.27 1.27)
				)
			)
		)
		(duplicate_pad_numbers_are_jumpers no)
		(fp_line
			(start 0.7874 -0.4064)
			(end 0.7874 0.4064)
			(stroke
				(width 0.1524)
				(type default)
			)
			(layer "F.SilkS")
		)
		(fp_line
			(start -0.7874 -0.4064)
			(end 0.00635 -0.4064)
			(stroke
				(width 0.1524)
				(type default)
			)
			(layer "F.SilkS")
		)
		(fp_line
			(start -0.01397 0.4064)
			(end -0.7874 0.4064)
			(stroke
				(width 0.1524)
				(type default)
			)
			(layer "F.SilkS")
		)
		(fp_line
			(start -0.12065 -0.305054)
			(end -0.12065 -0.2794)
			(stroke
				(width 0.1)
				(type default)
			)
			(layer "F.Fab")
		)
		(fp_line
			(start -0.67945 -0.305054)
			(end -0.12065 -0.305054)
			(stroke
				(width 0.1)
				(type default)
			)
			(layer "F.Fab")
		)
		(fp_line
			(start 0.67945 -0.3048)
			(end 0.67945 0.3048)
			(stroke
				(width 0.1)
				(type default)
			)
			(layer "F.Fab")
		)
		(fp_line
			(start 0.12065 -0.3048)
			(end 0.67945 -0.3048)
			(stroke
				(width 0.1)
				(type default)
			)
			(layer "F.Fab")
		)
		(fp_line
			(start 0.12065 -0.2794)
			(end 0.12065 -0.3048)
			(stroke
				(width 0.1)
				(type default)
			)
			(layer "F.Fab")
		)
		(fp_line
			(start -0.12065 -0.2794)
			(end 0.12065 -0.2794)
			(stroke
				(width 0.1)
				(type default)
			)
			(layer "F.Fab")
		)
		(fp_line
			(start 0.120396 0.2794)
			(end -0.12065 0.2794)
			(stroke
				(width 0.1)
				(type default)
			)
			(layer "F.Fab")
		)
		(fp_line
			(start -0.12065 0.2794)
			(end -0.12065 0.3048)
			(stroke
				(width 0.1)
				(type default)
			)
			(layer "F.Fab")
		)
		(fp_line
			(start 0.67945 0.3048)
			(end 0.120396 0.3048)
			(stroke
				(width 0.1)
				(type default)
			)
			(layer "F.Fab")
		)
		(fp_line
			(start 0.120396 0.3048)
			(end 0.120396 0.2794)
			(stroke
				(width 0.1)
				(type default)
			)
			(layer "F.Fab")
		)
		(fp_line
			(start -0.12065 0.3048)
			(end -0.67945 0.3048)
			(stroke
				(width 0.1)
				(type default)
			)
			(layer "F.Fab")
		)
		(fp_line
			(start -0.67945 0.3048)
			(end -0.67945 -0.305054)
			(stroke
				(width 0.1)
				(type default)
			)
			(layer "F.Fab")
		)
		(pad "1" smd rect
			(at -0.40005 0 270)
			(size 0.4572 0.508)
			(layers "F.Cu" "F.Mask" "F.Paste")
			(net "USB2_P0_R_DP")
		)
		(pad "2" smd rect
			(at 0.40005 0 270)
			(size 0.4572 0.508)
			(layers "F.Cu" "F.Mask" "F.Paste")
			(net "USB2_HOST_BMC_B_DP")
		)
	)
	(footprint ""
		(layer "F.Cu")
		(at 303.9872 -22.606 180)
		(property "Reference" "R4791"
			(at 0 0 180)
			(layer "F.SilkS")
			(hide yes)
			(effects
				(font
					(size 1.27 1.27)
				)
			)
		)
		(property "Value" ""
			(at 0 0 180)
			(layer "F.Fab")
			(effects
				(font
					(size 1.27 1.27)
				)
			)
		)
		(duplicate_pad_numbers_are_jumpers no)
		(fp_line
			(start 0.7874 0.4064)
			(end -0.7874 0.4064)
			(stroke
				(width 0.1524)
				(type default)
			)
			(layer "F.SilkS")
		)
		(fp_line
			(start 0.7874 -0.4064)
			(end 0.7874 0.4064)
			(stroke
				(width 0.1524)
				(type default)
			)
			(layer "F.SilkS")
		)
		(fp_line
			(start -0.7874 0.4064)
			(end -0.7874 -0.4064)
			(stroke
				(width 0.1524)
				(type default)
			)
			(layer "F.SilkS")
		)
		(fp_line
			(start -0.7874 -0.4064)
			(end 0.7874 -0.4064)
			(stroke
				(width 0.1524)
				(type default)
			)
			(layer "F.SilkS")
		)
		(fp_line
			(start 0.67945 0.3048)
			(end 0.120396 0.3048)
			(stroke
				(width 0.1)
				(type default)
			)
			(layer "F.Fab")
		)
		(fp_line
			(start 0.67945 -0.3048)
			(end 0.67945 0.3048)
			(stroke
				(width 0.1)
				(type default)
			)
			(layer "F.Fab")
		)
		(fp_line
			(start 0.12065 -0.2794)
			(end 0.12065 -0.3048)
			(stroke
				(width 0.1)
				(type default)
			)
			(layer "F.Fab")
		)
		(fp_line
			(start 0.12065 -0.3048)
			(end 0.67945 -0.3048)
			(stroke
				(width 0.1)
				(type default)
			)
			(layer "F.Fab")
		)
		(fp_line
			(start 0.120396 0.3048)
			(end 0.120396 0.2794)
			(stroke
				(width 0.1)
				(type default)
			)
			(layer "F.Fab")
		)
		(fp_line
			(start 0.120396 0.2794)
			(end -0.12065 0.2794)
			(stroke
				(width 0.1)
				(type default)
			)
			(layer "F.Fab")
		)
		(fp_line
			(start -0.12065 0.3048)
			(end -0.67945 0.3048)
			(stroke
				(width 0.1)
				(type default)
			)
			(layer "F.Fab")
		)
		(fp_line
			(start -0.12065 0.2794)
			(end -0.12065 0.3048)
			(stroke
				(width 0.1)
				(type default)
			)
			(layer "F.Fab")
		)
		(fp_line
			(start -0.12065 -0.2794)
			(end 0.12065 -0.2794)
			(stroke
				(width 0.1)
				(type default)
			)
			(layer "F.Fab")
		)
		(fp_line
			(start -0.12065 -0.305054)
			(end -0.12065 -0.2794)
			(stroke
				(width 0.1)
				(type default)
			)
			(layer "F.Fab")
		)
		(fp_line
			(start -0.67945 0.3048)
			(end -0.67945 -0.305054)
			(stroke
				(width 0.1)
				(type default)
			)
			(layer "F.Fab")
		)
		(fp_line
			(start -0.67945 -0.305054)
			(end -0.12065 -0.305054)
			(stroke
				(width 0.1)
				(type default)
			)
			(layer "F.Fab")
		)
		(pad "1" smd circle
			(at -0.40005 0 180)
			(size 0 0)
			(layers "F.Cu" "F.Mask" "F.Paste")
			(net "PWRGD_DSW_PWROK_TRIGGER")
		)
		(pad "2" smd circle
			(at 0.40005 0 180)
			(size 0 0)
			(layers "F.Cu" "F.Mask" "F.Paste")
			(net "GND")
		)
	)
)
